# SCM (Grand Teton) — schematic netlist excerpt (pin names and nets, part order shuffled) for the footprints in the layout excerpt that follows; sources: Cadence DE-HDL packaged netlist, KiCad conversion of 12092022_DA0F0TMDCD0_F0T_Management_Board_D_brd_V3_OCP.brd

PU41  NB695GDZ  NB695GD-Z IC  pkg QFN13_2X3  page 55
  VIN  = SW_P1V2_AUX_FLT
  PGND  = GND
  C1  = GND
  C0  = GND
  EN  = EN_P1V2_AUX_R
  \lp#\  = P1V2_AUX_VCC
  MODE  = P1V2_AUX_MODE
  SW  = SW_P1V2_AUX_SW
  BST  = SW_P1V2_AUX_BST
  \3v3\  = P1V2_AUX_VCC
  AGND  = GND
  VOUT  = P1V2_AUX
  PG  = PWRGD_P1V2_AUX_R

C324  Q_CAP  470PF 50V 10% X7R  pkg 0402  page 49 : A = HDD_LED_BUF_R ; B = GND

(kicad_pcb
	(version 20260206)
	(generator "pcbnew")
	(generator_version "10.0")
	(general
		(thickness 1.6)
		(legacy_teardrops no)
	)
	(paper "A4")
	(title_block
		(title "12092022_DA0F0TMDCD0_F0T_Management_Board_D_brd_V3_OCP.brd")
		(comment 1 "Grand Teton / footprints 178-179 of 1440")
	)
	(layers
		(0 "F.Cu" signal "TOP")
		(4 "In1.Cu" signal "GND")
		(6 "In2.Cu" signal "IN1")
		(8 "In3.Cu" signal "GND1")
		(10 "In4.Cu" signal "IN2")
		(12 "In5.Cu" signal "VCC")
		(14 "In6.Cu" signal "VCC1")
		(16 "In7.Cu" signal "IN3")
		(18 "In8.Cu" signal "GND2")
		(20 "In9.Cu" signal "IN4")
		(22 "In10.Cu" signal "GND3")
		(2 "B.Cu" signal "BOTTOM")
		(9 "F.Adhes" user "F.Adhesive")
		(11 "B.Adhes" user "B.Adhesive")
		(13 "F.Paste" user "Package Geometry/Pastemask Top")
		(15 "B.Paste" user "Package Geometry/Pastemask Bottom")
		(5 "F.SilkS" user "Ref Des/Silkscreen Top")
		(7 "B.SilkS" user "Ref Des/Silkscreen Bottom")
		(1 "F.Mask" user "Board Geometry/Soldermask Top")
		(3 "B.Mask" user "Board Geometry/Soldermask Bottom")
		(17 "Dwgs.User" user "User.Drawings")
		(19 "Cmts.User" user "User.Comments")
		(21 "Eco1.User" user "User.Eco1")
		(23 "Eco2.User" user "User.Eco2")
		(25 "Edge.Cuts" user "Board Geometry/Outline")
		(27 "Margin" user)
		(31 "F.CrtYd" user "Package Geometry/Place Bound Top")
		(29 "B.CrtYd" user "Package Geometry/Place Bound Bottom")
		(35 "F.Fab" user "Ref Des/Assembly Top")
		(33 "B.Fab" user "Ref Des/Assembly Bottom")
	)
	(footprint ""
		(layer "F.Cu")
		(at 28.575 -10.287 90)
		(property "Reference" "C324"
			(at 0 0 90)
			(layer "F.SilkS")
			(hide yes)
			(effects
				(font
					(size 1.27 1.27)
				)
			)
		)
		(property "Value" ""
			(at 0 0 90)
			(layer "F.Fab")
			(effects
				(font
					(size 1.27 1.27)
				)
			)
		)
		(duplicate_pad_numbers_are_jumpers no)
		(fp_line
			(start 0.7874 -0.4064)
			(end 0.7874 0.4064)
			(stroke
				(width 0.1524)
				(type default)
			)
			(layer "F.SilkS")
		)
		(fp_line
			(start -0.7874 -0.4064)
			(end 0.7874 -0.4064)
			(stroke
				(width 0.1524)
				(type default)
			)
			(layer "F.SilkS")
		)
		(fp_line
			(start 0.7874 0.4064)
			(end -0.7874 0.4064)
			(stroke
				(width 0.1524)
				(type default)
			)
			(layer "F.SilkS")
		)
		(fp_line
			(start -0.7874 0.4064)
			(end -0.7874 -0.4064)
			(stroke
				(width 0.1524)
				(type default)
			)
			(layer "F.SilkS")
		)
		(fp_line
			(start -0.12065 -0.305054)
			(end -0.12065 -0.2794)
			(stroke
				(width 0.1)
				(type default)
			)
			(layer "F.Fab")
		)
		(fp_line
			(start -0.67945 -0.305054)
			(end -0.12065 -0.305054)
			(stroke
				(width 0.1)
				(type default)
			)
			(layer "F.Fab")
		)
		(fp_line
			(start 0.67945 -0.3048)
			(end 0.67945 0.3048)
			(stroke
				(width 0.1)
				(type default)
			)
			(layer "F.Fab")
		)
		(fp_line
			(start 0.12065 -0.3048)
			(end 0.67945 -0.3048)
			(stroke
				(width 0.1)
				(type default)
			)
			(layer "F.Fab")
		)
		(fp_line
			(start 0.12065 -0.2794)
			(end 0.12065 -0.3048)
			(stroke
				(width 0.1)
				(type default)
			)
			(layer "F.Fab")
		)
		(fp_line
			(start -0.12065 -0.2794)
			(end 0.12065 -0.2794)
			(stroke
				(width 0.1)
				(type default)
			)
			(layer "F.Fab")
		)
		(fp_line
			(start 0.120396 0.2794)
			(end -0.12065 0.2794)
			(stroke
				(width 0.1)
				(type default)
			)
			(layer "F.Fab")
		)
		(fp_line
			(start -0.12065 0.2794)
			(end -0.12065 0.3048)
			(stroke
				(width 0.1)
				(type default)
			)
			(layer "F.Fab")
		)
		(fp_line
			(start 0.67945 0.3048)
			(end 0.120396 0.3048)
			(stroke
				(width 0.1)
				(type default)
			)
			(layer "F.Fab")
		)
		(fp_line
			(start 0.120396 0.3048)
			(end 0.120396 0.2794)
			(stroke
				(width 0.1)
				(type default)
			)
			(layer "F.Fab")
		)
		(fp_line
			(start -0.12065 0.3048)
			(end -0.67945 0.3048)
			(stroke
				(width 0.1)
				(type default)
			)
			(layer "F.Fab")
		)
		(fp_line
			(start -0.67945 0.3048)
			(end -0.67945 -0.305054)
			(stroke
				(width 0.1)
				(type default)
			)
			(layer "F.Fab")
		)
		(pad "1" smd circle
			(at -0.40005 0 90)
			(size 0 0)
			(layers "F.Cu" "F.Mask" "F.Paste")
			(net "HDD_LED_BUF_R")
		)
		(pad "2" smd circle
			(at 0.40005 0 90)
			(size 0 0)
			(layers "F.Cu" "F.Mask" "F.Paste")
			(net "GND")
		)
	)
	(footprint ""
		(layer "F.Cu")
		(at 81.744058 -72.680576 -90)
		(property "Reference" "PU41"
			(at -3.61823 5.860034 0)
			(unlocked yes)
			(layer "F.SilkS")
			(effects
				(font
					(size 0.7874 0.5842)
					(thickness 0.1524)
				)
				(justify left)
			)
		)
		(property "Value" ""
			(at 0 0 270)
			(layer "F.Fab")
			(effects
				(font
					(size 1.27 1.27)
				)
			)
		)
		(duplicate_pad_numbers_are_jumpers no)
		(fp_line
			(start -1.050036 1.549908)
			(end -1.016 1.549908)
			(stroke
				(width 0.1524)
				(type default)
			)
			(layer "F.SilkS")
		)
		(fp_line
			(start 1.016 1.549908)
			(end 1.050036 1.549908)
			(stroke
				(width 0.1524)
				(type default)
			)
			(layer "F.SilkS")
		)
		(fp_line
			(start 1.050036 1.549908)
			(end 1.050036 0.762)
			(stroke
				(width 0.1524)
				(type default)
			)
			(layer "F.SilkS")
		)
		(fp_line
			(start -1.050036 0.762)
			(end -1.050036 1.549908)
			(stroke
				(width 0.1524)
				(type default)
			)
			(layer "F.SilkS")
		)
		(fp_line
			(start -1.050036 -0.2286)
			(end -1.050036 0.2286)
			(stroke
				(width 0.1524)
				(type default)
			)
			(layer "F.SilkS")
		)
		(fp_line
			(start 1.050036 -0.762)
			(end 1.050036 -1.549908)
			(stroke
				(width 0.1524)
				(type default)
			)
			(layer "F.SilkS")
		)
		(fp_line
			(start -1.050036 -1.549908)
			(end -1.050036 -0.762)
			(stroke
				(width 0.1524)
				(type default)
			)
			(layer "F.SilkS")
		)
		(fp_line
			(start -1.016 -1.549908)
			(end -1.050036 -1.549908)
			(stroke
				(width 0.1524)
				(type default)
			)
			(layer "F.SilkS")
		)
		(fp_line
			(start 1.050036 -1.549908)
			(end 1.016 -1.549908)
			(stroke
				(width 0.1524)
				(type default)
			)
			(layer "F.SilkS")
		)
		(fp_poly
			(pts
				(xy -1.851914 -0.720344) (xy -1.411224 -0.499872) (xy -1.851914 -0.279654)
			)
			(stroke
				(width 0)
				(type default)
			)
			(fill yes)
			(layer "F.SilkS")
		)
		(fp_line
			(start -1.050036 1.549908)
			(end 1.050036 1.549908)
			(stroke
				(width 0.1)
				(type default)
			)
			(layer "F.Fab")
		)
		(fp_line
			(start 1.050036 1.549908)
			(end 1.050036 -1.549908)
			(stroke
				(width 0.1)
				(type default)
			)
			(layer "F.Fab")
		)
		(fp_line
			(start -1.050036 -1.549908)
			(end -1.050036 1.549908)
			(stroke
				(width 0.1)
				(type default)
			)
			(layer "F.Fab")
		)
		(fp_line
			(start 1.050036 -1.549908)
			(end -1.050036 -1.549908)
			(stroke
				(width 0.1)
				(type default)
			)
			(layer "F.Fab")
		)
		(fp_poly
			(pts
				(xy -1.851914 -0.720344) (xy -1.411224 -0.499872) (xy -1.851914 -0.279654)
			)
			(stroke
				(width 0)
				(type default)
			)
			(fill yes)
			(layer "F.Fab")
		)
		(pad "1" smd rect
			(at -0.54991 -0.499872)
			(size 0.254 1.4986)
			(layers "F.Cu" "F.Mask" "F.Paste")
			(net "SW_P1V2_AUX_FLT")
		)
		(pad "2" smd rect
			(at -0.54991 0.499872)
			(size 0.254 1.4986)
			(layers "F.Cu" "F.Mask" "F.Paste")
			(net "GND")
		)
		(pad "3" smd rect
			(at -0.750062 1.450086 270)
			(size 0.254 0.7112)
			(layers "F.Cu" "F.Mask" "F.Paste")
			(net "GND")
		)
		(pad "4" smd rect
			(at -0.249936 1.450086 270)
			(size 0.254 0.7112)
			(layers "F.Cu" "F.Mask" "F.Paste")
			(net "GND")
		)
		(pad "5" smd rect
			(at 0.249936 1.450086 270)
			(size 0.254 0.7112)
			(layers "F.Cu" "F.Mask" "F.Paste")
			(net "EN_P1V2_AUX_R")
		)
		(pad "6" smd rect
			(at 0.750062 1.450086 270)
			(size 0.254 0.7112)
			(layers "F.Cu" "F.Mask" "F.Paste")
			(net "P1V2_AUX_VCC")
		)
		(pad "7" smd rect
			(at 0.94996 0.499872)
			(size 0.254 0.7112)
			(layers "F.Cu" "F.Mask" "F.Paste")
			(net "P1V2_AUX_MODE")
		)
		(pad "8" smd rect
			(at 0.54991 0)
			(size 0.254 1.4986)
			(layers "F.Cu" "F.Mask" "F.Paste")
			(net "SW_P1V2_AUX_SW")
		)
		(pad "9" smd rect
			(at 0.94996 -0.499872)
			(size 0.254 0.7112)
			(layers "F.Cu" "F.Mask" "F.Paste")
			(net "SW_P1V2_AUX_BST")
		)
		(pad "10" smd rect
			(at 0.750062 -1.450086 270)
			(size 0.254 0.7112)
			(layers "F.Cu" "F.Mask" "F.Paste")
			(net "P1V2_AUX_VCC")
		)
		(pad "11" smd rect
			(at 0.249936 -1.450086 270)
			(size 0.254 0.7112)
			(layers "F.Cu" "F.Mask" "F.Paste")
			(net "GND")
		)
		(pad "12" smd rect
			(at -0.249936 -1.450086 270)
			(size 0.254 0.7112)
			(layers "F.Cu" "F.Mask" "F.Paste")
			(net "P1V2_AUX")
		)
		(pad "13" smd rect
			(at -0.750062 -1.450086 270)
			(size 0.254 0.7112)
			(layers "F.Cu" "F.Mask" "F.Paste")
			(net "PWRGD_P1V2_AUX_R")
		)
	)
)
